# BASEBOARD_FAB2 (Tioga Pass) — schematic netlist excerpt (pin names and nets, part order shuffled) for the footprints in the layout excerpt that follows; sources: Cadence DE-HDL packaged netlist, KiCad conversion of Wiwynn_Tioga_Pass_MB.brd

J4G3  SCONN288_H44441004  SCONN  pkg PIP  page 47
  \12v\(1)  = P12V_NVDIMM_ABC
  VSS(93)  = GND
  DQ(4)  = M_C_DQ<5>
  VSS(92)  = GND
  DQ(0)  = M_C_DQ<1>
  VSS(91)  = GND
  DQS9P  = M_C_DQS_DP<9>
  DQS9N  = M_C_DQS_DN<9>
  VSS(90)  = GND
  DQ(6)  = M_C_DQ<7>
  VSS(89)  = GND
  DQ(2)  = M_C_DQ<3>
  VSS(88)  = GND
  DQ(12)  = M_C_DQ<13>
  VSS(87)  = GND
  DQ(8)  = M_C_DQ<9>
  VSS(86)  = GND
  DQS10P  = M_C_DQS_DP<10>
  DQS10N  = M_C_DQS_DN<10>
  VSS(85)  = GND
  DQ(14)  = M_C_DQ<15>
  VSS(84)  = GND
  DQ(10)  = M_C_DQ<11>
  VSS(83)  = GND
  DQ(20)  = M_C_DQ<21>
  VSS(82)  = GND
  DQ(16)  = M_C_DQ<17>
  VSS(81)  = GND
  DQS11P  = M_C_DQS_DP<11>
  DQS11N  = M_C_DQS_DN<11>
  VSS(80)  = GND
  DQ(22)  = M_C_DQ<23>
  VSS(79)  = GND
  DQ(18)  = M_C_DQ<19>
  VSS(78)  = GND
  DQ(28)  = M_C_DQ<29>
  VSS(77)  = GND
  DQ(24)  = M_C_DQ<25>
  VSS(76)  = GND
  DQS12P  = M_C_DQS_DP<12>
  DQS12N  = M_C_DQS_DN<12>
  VSS(75)  = GND
  DQ(30)  = M_C_DQ<31>
  VSS(74)  = GND
  DQ(26)  = M_C_DQ<27>
  VSS(73)  = GND
  CB(4)  = M_C_ECC<5>
  VSS(72)  = GND
  CB(0)  = M_C_ECC<1>
  VSS(71)  = GND
  DQS17P  = M_C_DQS_DP<17>
  DQS17N  = M_C_DQS_DN<17>
  VSS(70)  = GND
  CB(6)  = M_C_ECC<7>
  VSS(69)  = GND
  CB(2)  = M_C_ECC<3>
  VSS(68)  = GND
  RESET_N  = M_ABC_RST_N
  VDD(25)  = PVDDQ_ABC
  CKE(0)  = M_C_CKE<0>
  VDD(24)  = PVDDQ_ABC
  ACT_N  = M_C_ACT_N
  BG(0)  = M_C_BG<0>
  VDD(23)  = PVDDQ_ABC
  A12  = M_C_MA<12>
  A9  = M_C_MA<9>
  VDD(22)  = PVDDQ_ABC
  A8  = M_C_MA<8>
  A6  = M_C_MA<6>
  VDD(21)  = PVDDQ_ABC
  A3  = M_C_MA<3>
  A1  = M_C_MA<1>
  VDD(20)  = PVDDQ_ABC
  CK0P  = M_C_CLK_DP<0>
  CK0N  = M_C_CLK_DN<0>
  VDD(19)  = PVDDQ_ABC
  VTT(1)  = PVTT_ABC
  EVENT_N  = FM_DIMM_EVENT_COD_N
  A0  = M_C_MA<0>
  VDD(18)  = PVDDQ_ABC
  BA(0)  = M_C_BA<0>
  A16_RAS_N  = M_C_MA<16>
  VDD(17)  = PVDDQ_ABC
  S0_N  = M_C_CS_N<0>
  VDD(16)  = PVDDQ_ABC
  A15_CAS_N  = M_C_MA<15>
  ODT(0)  = M_C_ODT<0>
  VDD(15)  = PVDDQ_ABC
  S1_N  = M_C_CS_N<1>
  VDD(14)  = PVDDQ_ABC
  ODT(1)  = M_C_ODT<1>
  VDD(13)  = PVDDQ_ABC
  S2_N_C(0)  = M_C_CS_N<2>
  VSS(67)  = GND
  DQ(36)  = M_C_DQ<37>
  VSS(66)  = GND
  DQ(32)  = M_C_DQ<33>
  VSS(65)  = GND
  DQS13P  = M_C_DQS_DP<13>
  DQS13N  = M_C_DQS_DN<13>
  VSS(64)  = GND
  DQ(38)  = M_C_DQ<39>
  VSS(63)  = GND
  DQ(34)  = M_C_DQ<35>
  VSS(62)  = GND
  DQ(44)  = M_C_DQ<45>
  VSS(61)  = GND
  DQ(40)  = M_C_DQ<41>
  VSS(60)  = GND
  DQS14P  = M_C_DQS_DP<14>
  DQS14N  = M_C_DQS_DN<14>
  VSS(59)  = GND
  DQ(46)  = M_C_DQ<47>
  VSS(58)  = GND
  DQ(42)  = M_C_DQ<43>
  VSS(57)  = GND
  DQ(52)  = M_C_DQ<53>
  VSS(56)  = GND
  DQ(48)  = M_C_DQ<49>
  VSS(55)  = GND
  DQS15P  = M_C_DQS_DP<15>
  DQS15N  = M_C_DQS_DN<15>
  VSS(54)  = GND
  DQ(54)  = M_C_DQ<55>
  VSS(53)  = GND
  DQ(50)  = M_C_DQ<51>
  VSS(52)  = GND
  DQ(60)  = M_C_DQ<61>
  VSS(51)  = GND
  DQ(56)  = M_C_DQ<57>
  VSS(50)  = GND
  DQS16P  = M_C_DQS_DP<16>
  DQS16N  = M_C_DQS_DN<16>
  VSS(49)  = GND
  DQ(62)  = M_C_DQ<63>
  VSS(48)  = GND
  DQ(58)  = M_C_DQ<59>
  VSS(47)  = GND
  SA(0)  = GND
  SA(1)  = GND
  SCL  = SMB_DDR_ABC_VPP_SCL
  VPP(4)  = PVPP_ABC
  VPP(3)  = PVPP_ABC
  RFU(2)  = TP_CH_C_DIMM_C0_RFU_2
  \12v\(0)  = P12V_NVDIMM_ABC
  VREFCA  = M_C_VREF
  VSS(46)  = GND
  DQ(5)  = M_C_DQ<4>
  VSS(45)  = GND
  DQ(1)  = M_C_DQ<0>
  VSS(44)  = GND
  DQS0N  = M_C_DQS_DN<0>
  DQS0P  = M_C_DQS_DP<0>
  VSS(43)  = GND
  DQ(7)  = M_C_DQ<6>
  VSS(42)  = GND
  DQ(3)  = M_C_DQ<2>
  VSS(41)  = GND
  DQ(13)  = M_C_DQ<12>
  VSS(40)  = GND
  DQ(9)  = M_C_DQ<8>
  VSS(39)  = GND
  DQS1N  = M_C_DQS_DN<1>
  DQS1P  = M_C_DQS_DP<1>
  VSS(38)  = GND
  DQ(15)  = M_C_DQ<14>
  VSS(37)  = GND
  DQ(11)  = M_C_DQ<10>
  VSS(36)  = GND
  DQ(21)  = M_C_DQ<20>
  VSS(35)  = GND
  DQ(17)  = M_C_DQ<16>
  VSS(34)  = GND
  DQS2N  = M_C_DQS_DN<2>
  DQS2P  = M_C_DQS_DP<2>
  VSS(33)  = GND
  DQ(23)  = M_C_DQ<22>
  VSS(32)  = GND
  DQ(19)  = M_C_DQ<18>
  VSS(31)  = GND
  DQ(29)  = M_C_DQ<28>
  VSS(30)  = GND
  DQ(25)  = M_C_DQ<24>
  VSS(29)  = GND
  DQS3N  = M_C_DQS_DN<3>
  DQS3P  = M_C_DQS_DP<3>
  VSS(28)  = GND
  DQ(31)  = M_C_DQ<30>
  VSS(27)  = GND
  DQ(27)  = M_C_DQ<26>
  VSS(26)  = GND
  CB(5)  = M_C_ECC<4>
  VSS(25)  = GND
  CB(1)  = M_C_ECC<0>
  VSS(24)  = GND
  DQS8N  = M_C_DQS_DN<8>
  DQS8P  = M_C_DQS_DP<8>
  VSS(23)  = GND
  CB(7)  = M_C_ECC<6>
  VSS(22)  = GND
  CB(3)  = M_C_ECC<2>
  VSS(21)  = GND
  CKE(1)  = M_C_CKE<1>
  VDD(12)  = PVDDQ_ABC
  RFU(0)  = TP_CH_C_DIMM_C0_RFU_0
  VDD(11)  = PVDDQ_ABC
  BG(1)  = M_C_BG<1>
  ALERT_N  = M_C_ALERT_N
  VDD(10)  = PVDDQ_ABC
  A11  = M_C_MA<11>
  A7  = M_C_MA<7>
  VDD(9)  = PVDDQ_ABC
  A5  = M_C_MA<5>
  A4  = M_C_MA<4>
  VDD(8)  = PVDDQ_ABC
  A2  = M_C_MA<2>
  VDD(7)  = PVDDQ_ABC
  CK1P  = M_C_CLK_DP<1>
  CK1N  = M_C_CLK_DN<1>
  VDD(6)  = PVDDQ_ABC
  VTT(0)  = PVTT_ABC
  PAR  = M_C_PAR
  VDD(5)  = PVDDQ_ABC
  BA(1)  = M_C_BA<1>
  A10  = M_C_MA<10>
  VDD(4)  = PVDDQ_ABC
  RFU(1)  = TP_CH_C_DIMM_C0_RFU_1
  A14_WE_N  = M_C_MA<14>
  VDD(3)  = PVDDQ_ABC
  SAVE_N_NC  = FM_ADR_COMPLETE_ABC_N
  VDD(2)  = PVDDQ_ABC
  A13  = M_C_MA<13>
  VDD(1)  = PVDDQ_ABC
  A17  = M_C_MA<17>
  C(2)  = M_C_C<2>
  VDD(0)  = PVDDQ_ABC
  S3_N_C(1)  = M_C_CS_N<3>
  SA(2)  = PVPP_ABC
  VSS(20)  = GND
  DQ(37)  = M_C_DQ<36>
  VSS(19)  = GND
  DQ(33)  = M_C_DQ<32>
  VSS(18)  = GND
  DQS4N  = M_C_DQS_DN<4>
  DQS4P  = M_C_DQS_DP<4>
  VSS(17)  = GND
  DQ(39)  = M_C_DQ<38>
  VSS(16)  = GND
  DQ(35)  = M_C_DQ<34>
  VSS(15)  = GND
  DQ(45)  = M_C_DQ<44>
  VSS(14)  = GND
  DQ(41)  = M_C_DQ<40>
  VSS(13)  = GND
  DQS5N  = M_C_DQS_DN<5>
  DQS5P  = M_C_DQS_DP<5>
  VSS(12)  = GND
  DQ(47)  = M_C_DQ<46>
  VSS(11)  = GND
  DQ(43)  = M_C_DQ<42>
  VSS(10)  = GND
  DQ(53)  = M_C_DQ<52>
  VSS(9)  = GND
  DQ(49)  = M_C_DQ<48>
  VSS(8)  = GND
  DQS6N  = M_C_DQS_DN<6>
  DQS6P  = M_C_DQS_DP<6>
  VSS(7)  = GND
  DQ(55)  = M_C_DQ<54>
  VSS(6)  = GND
  DQ(51)  = M_C_DQ<50>
  VSS(5)  = GND
  DQ(61)  = M_C_DQ<60>
  VSS(4)  = GND
  DQ(57)  = M_C_DQ<56>
  VSS(3)  = GND
  DQS7N  = M_C_DQS_DN<7>
  DQS7P  = M_C_DQS_DP<7>
  VSS(2)  = GND
  DQ(63)  = M_C_DQ<62>
  VSS(1)  = GND
  DQ(59)  = M_C_DQ<58>
  VSS(0)  = GND
  VDDSPD  = PVPP_ABC
  SDA  = SMB_DDR_ABC_VPP_SDA
  VPP(1)  = PVPP_ABC
  VPP(0)  = PVPP_ABC
  VPP(2)  = PVPP_ABC

(kicad_pcb
	(version 20260206)
	(generator "pcbnew")
	(generator_version "10.0")
	(general
		(thickness 1.6)
		(legacy_teardrops no)
	)
	(paper "A4")
	(title_block
		(title "Wiwynn_Tioga_Pass_MB.brd")
		(comment 1 "Tioga Pass / footprint 1441 of 4770 (J4G3), pads 203-251 of 291")
	)
	(layers
		(0 "F.Cu" signal "TOP")
		(4 "In1.Cu" signal "L2GND")
		(6 "In2.Cu" signal "L3")
		(8 "In3.Cu" signal "L4GND")
		(10 "In4.Cu" signal "L5")
		(12 "In5.Cu" signal "L6GND")
		(14 "In6.Cu" signal "L7VCC")
		(16 "In7.Cu" signal "L8VCC")
		(18 "In8.Cu" signal "L9GND")
		(20 "In9.Cu" signal "L10")
		(22 "In10.Cu" signal "L11GND")
		(24 "In11.Cu" signal "L12")
		(26 "In12.Cu" signal "L13GND")
		(2 "B.Cu" signal "BOTTOM")
		(9 "F.Adhes" user "F.Adhesive")
		(11 "B.Adhes" user "B.Adhesive")
		(13 "F.Paste" user "Package Geometry/Pastemask Top")
		(15 "B.Paste" user "Package Geometry/Pastemask Bottom")
		(5 "F.SilkS" user "Ref Des/Silkscreen Top")
		(7 "B.SilkS" user "Ref Des/Silkscreen Bottom")
		(1 "F.Mask" user "Board Geometry/Soldermask Top")
		(3 "B.Mask" user "Board Geometry/Soldermask Bottom")
		(17 "Dwgs.User" user "User.Drawings")
		(19 "Cmts.User" user "User.Comments")
		(21 "Eco1.User" user "User.Eco1")
		(23 "Eco2.User" user "User.Eco2")
		(25 "Edge.Cuts" user "Board Geometry/Outline")
		(27 "Margin" user)
		(31 "F.CrtYd" user "Package Geometry/Place Bound Top")
		(29 "B.CrtYd" user "Package Geometry/Place Bound Bottom")
		(35 "F.Fab" user "Ref Des/Assembly Top")
		(33 "B.Fab" user "Ref Des/Assembly Bottom")
	)
	(footprint ""
		(layer "F.Cu")
		(at 194.700398 3.778758 90)
		(property "Reference" "J4G3"
			(at 6.800088 37.20211 0)
			(unlocked yes)
			(layer "F.SilkS")
			(effects
				(font
					(size 0.7874 0.5842)
					(thickness 0.1524)
				)
				(justify left)
			)
		)
		(property "Value" ""
			(at 0 0 90)
			(layer "F.Fab")
			(effects
				(font
					(size 1.27 1.27)
				)
			)
		)
		(duplicate_pad_numbers_are_jumpers no)
		(pad "200" smd rect
			(at 4.59994 46.74997 90)
			(size 1.8034 0.508)
			(layers "F.Cu" "F.Mask" "F.Paste")
			(net "GND")
		)
		(pad "201" smd rect
			(at 4.59994 47.600108 90)
			(size 1.8034 0.508)
			(layers "F.Cu" "F.Mask" "F.Paste")
			(net "M_C_ECC<2>")
		)
		(pad "202" smd rect
			(at 4.59994 48.449992 90)
			(size 1.8034 0.508)
			(layers "F.Cu" "F.Mask" "F.Paste")
			(net "GND")
		)
		(pad "203" smd rect
			(at 4.59994 49.299876 90)
			(size 1.8034 0.508)
			(layers "F.Cu" "F.Mask" "F.Paste")
			(net "M_C_CKE<1>")
		)
		(pad "204" smd rect
			(at 4.59994 50.150014 90)
			(size 1.8034 0.508)
			(layers "F.Cu" "F.Mask" "F.Paste")
			(net "PVDDQ_ABC")
		)
		(pad "205" smd rect
			(at 4.59994 50.999898 90)
			(size 1.8034 0.508)
			(layers "F.Cu" "F.Mask" "F.Paste")
			(net "TP_CH_C_DIMM_C0_RFU_0")
		)
		(pad "206" smd rect
			(at 4.59994 51.850036 90)
			(size 1.8034 0.508)
			(layers "F.Cu" "F.Mask" "F.Paste")
			(net "PVDDQ_ABC")
		)
		(pad "207" smd rect
			(at 4.59994 52.69992 90)
			(size 1.8034 0.508)
			(layers "F.Cu" "F.Mask" "F.Paste")
			(net "M_C_BG<1>")
		)
		(pad "208" smd rect
			(at 4.59994 53.550058 90)
			(size 1.8034 0.508)
			(layers "F.Cu" "F.Mask" "F.Paste")
			(net "M_C_ALERT_N")
		)
		(pad "209" smd rect
			(at 4.59994 54.399942 90)
			(size 1.8034 0.508)
			(layers "F.Cu" "F.Mask" "F.Paste")
			(net "PVDDQ_ABC")
		)
		(pad "210" smd rect
			(at 4.59994 55.25008 90)
			(size 1.8034 0.508)
			(layers "F.Cu" "F.Mask" "F.Paste")
			(net "M_C_MA<11>")
		)
		(pad "211" smd rect
			(at 4.59994 56.099964 90)
			(size 1.8034 0.508)
			(layers "F.Cu" "F.Mask" "F.Paste")
			(net "M_C_MA<7>")
		)
		(pad "212" smd rect
			(at 4.59994 56.950102 90)
			(size 1.8034 0.508)
			(layers "F.Cu" "F.Mask" "F.Paste")
			(net "PVDDQ_ABC")
		)
		(pad "213" smd rect
			(at 4.59994 57.799986 90)
			(size 1.8034 0.508)
			(layers "F.Cu" "F.Mask" "F.Paste")
			(net "M_C_MA<5>")
		)
		(pad "214" smd rect
			(at 4.59994 58.650124 90)
			(size 1.8034 0.508)
			(layers "F.Cu" "F.Mask" "F.Paste")
			(net "M_C_MA<4>")
		)
		(pad "215" smd rect
			(at 4.59994 59.500008 90)
			(size 1.8034 0.508)
			(layers "F.Cu" "F.Mask" "F.Paste")
			(net "PVDDQ_ABC")
		)
		(pad "216" smd rect
			(at 4.59994 60.349892 90)
			(size 1.8034 0.508)
			(layers "F.Cu" "F.Mask" "F.Paste")
			(net "M_C_MA<2>")
		)
		(pad "217" smd rect
			(at 4.59994 61.20003 90)
			(size 1.8034 0.508)
			(layers "F.Cu" "F.Mask" "F.Paste")
			(net "PVDDQ_ABC")
		)
		(pad "218" smd rect
			(at 4.59994 62.049914 90)
			(size 1.8034 0.508)
			(layers "F.Cu" "F.Mask" "F.Paste")
			(net "M_C_CLK_DP<1>")
		)
		(pad "219" smd rect
			(at 4.59994 62.900052 90)
			(size 1.8034 0.508)
			(layers "F.Cu" "F.Mask" "F.Paste")
			(net "M_C_CLK_DN<1>")
		)
		(pad "220" smd rect
			(at 4.59994 63.749936 90)
			(size 1.8034 0.508)
			(layers "F.Cu" "F.Mask" "F.Paste")
			(net "PVDDQ_ABC")
		)
		(pad "221" smd rect
			(at 4.59994 64.600074 90)
			(size 1.8034 0.508)
			(layers "F.Cu" "F.Mask" "F.Paste")
			(net "PVTT_ABC")
		)
		(pad "222" smd rect
			(at 4.59994 70.550024 90)
			(size 1.8034 0.508)
			(layers "F.Cu" "F.Mask" "F.Paste")
			(net "M_C_PAR")
		)
		(pad "223" smd rect
			(at 4.59994 71.399908 90)
			(size 1.8034 0.508)
			(layers "F.Cu" "F.Mask" "F.Paste")
			(net "PVDDQ_ABC")
		)
		(pad "224" smd rect
			(at 4.59994 72.250046 90)
			(size 1.8034 0.508)
			(layers "F.Cu" "F.Mask" "F.Paste")
			(net "M_C_BA<1>")
		)
		(pad "225" smd rect
			(at 4.59994 73.09993 90)
			(size 1.8034 0.508)
			(layers "F.Cu" "F.Mask" "F.Paste")
			(net "M_C_MA<10>")
		)
		(pad "226" smd rect
			(at 4.59994 73.950068 90)
			(size 1.8034 0.508)
			(layers "F.Cu" "F.Mask" "F.Paste")
			(net "PVDDQ_ABC")
		)
		(pad "227" smd rect
			(at 4.59994 74.799952 90)
			(size 1.8034 0.508)
			(layers "F.Cu" "F.Mask" "F.Paste")
			(net "TP_CH_C_DIMM_C0_RFU_1")
		)
		(pad "228" smd rect
			(at 4.59994 75.65009 90)
			(size 1.8034 0.508)
			(layers "F.Cu" "F.Mask" "F.Paste")
			(net "M_C_MA<14>")
		)
		(pad "229" smd rect
			(at 4.59994 76.499974 90)
			(size 1.8034 0.508)
			(layers "F.Cu" "F.Mask" "F.Paste")
			(net "PVDDQ_ABC")
		)
		(pad "230" smd rect
			(at 4.59994 77.350112 90)
			(size 1.8034 0.508)
			(layers "F.Cu" "F.Mask" "F.Paste")
			(net "FM_ADR_COMPLETE_ABC_N")
		)
		(pad "231" smd rect
			(at 4.59994 78.199996 90)
			(size 1.8034 0.508)
			(layers "F.Cu" "F.Mask" "F.Paste")
			(net "PVDDQ_ABC")
		)
		(pad "232" smd rect
			(at 4.59994 79.04988 90)
			(size 1.8034 0.508)
			(layers "F.Cu" "F.Mask" "F.Paste")
			(net "M_C_MA<13>")
		)
		(pad "233" smd rect
			(at 4.59994 79.900018 90)
			(size 1.8034 0.508)
			(layers "F.Cu" "F.Mask" "F.Paste")
			(net "PVDDQ_ABC")
		)
		(pad "234" smd rect
			(at 4.59994 80.749902 90)
			(size 1.8034 0.508)
			(layers "F.Cu" "F.Mask" "F.Paste")
			(net "M_C_MA<17>")
		)
		(pad "235" smd rect
			(at 4.59994 81.60004 90)
			(size 1.8034 0.508)
			(layers "F.Cu" "F.Mask" "F.Paste")
			(net "M_C_C<2>")
		)
		(pad "236" smd rect
			(at 4.59994 82.449924 90)
			(size 1.8034 0.508)
			(layers "F.Cu" "F.Mask" "F.Paste")
			(net "PVDDQ_ABC")
		)
		(pad "237" smd rect
			(at 4.59994 83.300062 90)
			(size 1.8034 0.508)
			(layers "F.Cu" "F.Mask" "F.Paste")
			(net "M_C_CS_N<3>")
		)
		(pad "238" smd rect
			(at 4.59994 84.149946 90)
			(size 1.8034 0.508)
			(layers "F.Cu" "F.Mask" "F.Paste")
			(net "PVPP_ABC")
		)
		(pad "239" smd rect
			(at 4.59994 85.000084 90)
			(size 1.8034 0.508)
			(layers "F.Cu" "F.Mask" "F.Paste")
			(net "GND")
		)
		(pad "240" smd rect
			(at 4.59994 85.849968 90)
			(size 1.8034 0.508)
			(layers "F.Cu" "F.Mask" "F.Paste")
			(net "M_C_DQ<36>")
		)
		(pad "241" smd rect
			(at 4.59994 86.700106 90)
			(size 1.8034 0.508)
			(layers "F.Cu" "F.Mask" "F.Paste")
			(net "GND")
		)
		(pad "242" smd rect
			(at 4.59994 87.54999 90)
			(size 1.8034 0.508)
			(layers "F.Cu" "F.Mask" "F.Paste")
			(net "M_C_DQ<32>")
		)
		(pad "243" smd rect
			(at 4.59994 88.399874 90)
			(size 1.8034 0.508)
			(layers "F.Cu" "F.Mask" "F.Paste")
			(net "GND")
		)
		(pad "244" smd rect
			(at 4.59994 89.250012 90)
			(size 1.8034 0.508)
			(layers "F.Cu" "F.Mask" "F.Paste")
			(net "M_C_DQS_DN<4>")
		)
		(pad "245" smd rect
			(at 4.59994 90.099896 90)
			(size 1.8034 0.508)
			(layers "F.Cu" "F.Mask" "F.Paste")
			(net "M_C_DQS_DP<4>")
		)
		(pad "246" smd rect
			(at 4.59994 90.950034 90)
			(size 1.8034 0.508)
			(layers "F.Cu" "F.Mask" "F.Paste")
			(net "GND")
		)
		(pad "247" smd rect
			(at 4.59994 91.799918 90)
			(size 1.8034 0.508)
			(layers "F.Cu" "F.Mask" "F.Paste")
			(net "M_C_DQ<38>")
		)
		(pad "248" smd rect
			(at 4.59994 92.650056 90)
			(size 1.8034 0.508)
			(layers "F.Cu" "F.Mask" "F.Paste")
			(net "GND")
		)
	)
)
